# T6G (Grand Teton) — schematic netlist excerpt (pin names and nets, part order shuffled) for the footprints in the layout excerpt that follows; sources: Cadence DE-HDL packaged netlist, KiCad conversion of 04192023_DAF0TMB3IC0_F0TG_MB_C_brd_V02_OCP.brd

U6002  TUSB8042AIRGCR  IC  pkg VQFN64_TH_0-5_9X9XC  page 178
  USB_DP_DN1  = USB_HUB2_TI_USB_DP_DN1_MRP_CFG_STRAP
  USB_DM_DN1  = NC
  USB_SSTXP_DN1  = NC
  USB_SSTXM_DN1  = NC
  VDD_5  = USB_HUB2_TI_VDD_MRP_USB3DN_TXDM1
  USB_SSRXP_DN1  = USB_HUB2_TI_USB_SSRXP_DN1_MRP_VDD12
  USB_SSRXM_DN1  = NC
  VDD_8  = USB_HUB2_TI_VDD_MRP_USB3DN_RXDM1
  USB_DP_DN2  = USB2_CPU0_P0_HUB2_R_DP
  USB_DM_DN2  = USB2_CPU0_P0_HUB2_R_DN
  USB_SSTXP_DN2  = USB3_CPU0_BMC_HUB2_TX_DP
  USB_SSTXM_DN2  = USB3_CPU0_BMC_HUB2_TX_DN
  VDD_13  = P1V2_CPU0_USB2_DVDD12
  USB_SSRXP_DN2  = USB3_CPU0_BMC_RX_C2_DP
  USB_SSRXM_DN2  = USB3_CPU0_BMC_RX_C2_DN
  VDD33_16  = USB_HUB2_TI_VDD33_MRP_PROG_FUNC7
  USB_DP_DN3  = USB_HUB2_TI_USB_DP_DN3_MRP_VDD12
  USB_DM_DN3  = USB_HUB2_TI_USB_DM_DN3_MRP_VDD33
  USB_SSTXP_DN3  = NC
  USB_SSTXM_DN3  = NC
  VDD_21  = USB_HUB2_TI_VDD_MRP_USB3DN_TXDP3
  USB_SSRXP_DN3  = NC
  USB_SSRXM_DN3  = USB_HUB2_TI_USB_SSRXM_DN3_MRP_VDD12
  USB_DP_DN4  = NC
  USB_DM_DN4  = NC
  USB_SSTXP_DN4  = NC
  USB_SSTXM_DN4  = NC
  VDD_28  = USB_HUB2_TI_VDD_MRP_USB3DN_TXDP4
  USB_SSRXP_DN4  = NC
  USB_SSRXM_DN4  = USB_HUB2_TI_USB_SSRXM_DN4_MRP_VDD12
  VDD_31  = USB_HUB2_TI_VDD_MRP_USB3DN_RXDP4
  \pwrctl4||baten4\  = NC
  \pwrctl3||baten3\  = USB_HUB2_TI_PWRCTL3_MRP_VDD33
  VDD33_34  = USB_HUB2_TI_VDD33_MRP_PRT_CTL4_GANGPWR
  \pwrctl2||baten2\  = USB_HUB2_TI_PWRCTL2_MRP_VDD12
  \pwrctl1||baten1\  = NC
  \sda||smbdat\  = SMB_USB_HUB2_TI_SDA_MRP_PRT_CTL2
  \scl||smbclk\  = SMB_USB_HUB2_TI_SCL_MRP_PRT_CTL1
  \smbusz||ss_suspend\  = USB_HUB2_TI_SMBUSZ_MRP_PROG_FUNC2
  \fullpwrmgmtz||fullautoz||smba1||ss_up\  = USB_HUB2_TI_FULLPWRMGMTZ_MRP_PROG_FUNC3
  PWRCTL_POL  = USB_HUB2_TI_PWRCTL_POL_MRP_VBUS_DET
  \ganged||smba2||hs_up\  = USB_HUB2_TI_GANGED_MRP_I2C_SLV_CFG0
  OVERCUR4Z  = USB_HUB2_TI_OVERCUR4_MRP_I2C_SLV_CFG1
  OVERCUR3Z  = USB_HUB2_TI_OVERCUR3_MRP_CFG_BC_EN
  \autoenz||hs_suspend\  = USB_HUB2_TI_HS_SUSPEND_MRP_CFG_NON_REM
  OVERCUR1Z  = USB_HUB2_TI_OVERCUR1_MRP_PROG_FUNC4
  OVERCUR2Z  = USB_HUB2_TI_OVERCUR2_MRP_PROG_FUNC5
  USB_VBUS  = USB_HUB2_TI_USB_VBUS_MRP_RESET_N
  TEST  = USB_HUB2_TI_TEST_MRP_PROG_FUNC6
  GRSTZ  = USB_HUB2_TI_GRSTZ_MRP_PROG_FUNC1
  VDD_51  = P1V2_CPU0_USB2_DVDD12
  VDD33_52  = P3V3_AUX_CPU0_USB2_AVDD33
  USB_DP_UP  = USB2_CPU0_P0_R2_DP
  USB_DM_UP  = USB2_CPU0_P0_R2_DN
  USB_SSTXP_UP  = USB3_CPU0_BMC_RX_HUB2_DP
  USB_SSTXM_UP  = USB3_CPU0_BMC_RX_HUB2_DN
  VDD_57  = P1V2_CPU0_USB2_DVDD12
  USB_SSRXP_UP  = USB3_CPU0_BMC_TX_C2_DP
  USB_SSRXM_UP  = USB3_CPU0_BMC_TX_C2_DN
  NC_1  = USB_HUB2_TI_NC_MRP_ATEST
  XO  = XTAL_USB_CPU0_HUB2_XOUT
  XI  = XTAL_USB_CPU0_HUB2_XIN
  VDD33_63  = P3V3_AUX_CPU0_USB2_AVDD33
  USB_R1  = USB_HUB2_TI_USB_R1_MRP_RBIAS
  TH_VSS  = GND

(kicad_pcb
	(version 20260206)
	(generator "pcbnew")
	(generator_version "10.0")
	(general
		(thickness 1.6)
		(legacy_teardrops no)
	)
	(paper "A4")
	(title_block
		(title "04192023_DAF0TMB3IC0_F0TG_MB_C_brd_V02_OCP.brd")
		(comment 1 "Grand Teton / footprint 2863 of 8354 (U6002), pads 45-65 of 65")
	)
	(layers
		(0 "F.Cu" signal "TOP")
		(4 "In1.Cu" signal "GND")
		(6 "In2.Cu" signal "IN1")
		(8 "In3.Cu" signal "GND1")
		(10 "In4.Cu" signal "IN2")
		(12 "In5.Cu" signal "GND2")
		(14 "In6.Cu" signal "IN3")
		(16 "In7.Cu" signal "GND3")
		(18 "In8.Cu" signal "VCC")
		(20 "In9.Cu" signal "VCC1")
		(22 "In10.Cu" signal "GND4")
		(24 "In11.Cu" signal "IN4")
		(26 "In12.Cu" signal "GND5")
		(28 "In13.Cu" signal "IN5")
		(30 "In14.Cu" signal "GND6")
		(32 "In15.Cu" signal "IN6")
		(34 "In16.Cu" signal "GND7")
		(2 "B.Cu" signal "BOTTOM")
		(9 "F.Adhes" user "F.Adhesive")
		(11 "B.Adhes" user "B.Adhesive")
		(13 "F.Paste" user "Package Geometry/Pastemask Top")
		(15 "B.Paste" user "Package Geometry/Pastemask Bottom")
		(5 "F.SilkS" user "Ref Des/Silkscreen Top")
		(7 "B.SilkS" user "Ref Des/Silkscreen Bottom")
		(1 "F.Mask" user "Board Geometry/Soldermask Top")
		(3 "B.Mask" user "Board Geometry/Soldermask Bottom")
		(17 "Dwgs.User" user "User.Drawings")
		(19 "Cmts.User" user "User.Comments")
		(21 "Eco1.User" user "User.Eco1")
		(23 "Eco2.User" user "User.Eco2")
		(25 "Edge.Cuts" user "Board Geometry/Outline")
		(27 "Margin" user)
		(31 "F.CrtYd" user "Package Geometry/Place Bound Top")
		(29 "B.CrtYd" user "Package Geometry/Place Bound Bottom")
		(35 "F.Fab" user "Ref Des/Assembly Top")
		(33 "B.Fab" user "Ref Des/Assembly Bottom")
	)
	(footprint ""
		(layer "F.Cu")
		(at 112.79886 -31.497778 90)
		(property "Reference" "U6002"
			(at -4.285742 -6.178804 90)
			(unlocked yes)
			(layer "F.SilkS")
			(effects
				(font
					(size 0.7874 0.5842)
					(thickness 0.1524)
				)
				(justify left)
			)
		)
		(property "Value" ""
			(at 0 0 90)
			(layer "F.Fab")
			(effects
				(font
					(size 1.27 1.27)
				)
			)
		)
		(duplicate_pad_numbers_are_jumpers no)
		(pad "45" smd circle
			(at 4.400042 -2.249932)
			(size 0 0)
			(layers "F.Cu" "F.Mask" "F.Paste")
			(net "USB_HUB2_TI_HS_SUSPEND_MRP_CFG_NON_REM")
		)
		(pad "46" smd circle
			(at 4.400042 -2.750058)
			(size 0 0)
			(layers "F.Cu" "F.Mask" "F.Paste")
			(net "USB_HUB2_TI_OVERCUR1_MRP_PROG_FUNC4")
		)
		(pad "47" smd circle
			(at 4.400042 -3.24993)
			(size 0 0)
			(layers "F.Cu" "F.Mask" "F.Paste")
			(net "USB_HUB2_TI_OVERCUR2_MRP_PROG_FUNC5")
		)
		(pad "48" smd circle
			(at 4.400042 -3.750056)
			(size 0 0)
			(layers "F.Cu" "F.Mask" "F.Paste")
			(net "USB_HUB2_TI_USB_VBUS_MRP_RESET_N")
		)
		(pad "49" smd circle
			(at 3.750056 -4.400042 90)
			(size 0 0)
			(layers "F.Cu" "F.Mask" "F.Paste")
			(net "USB_HUB2_TI_TEST_MRP_PROG_FUNC6")
		)
		(pad "50" smd circle
			(at 3.24993 -4.400042 90)
			(size 0 0)
			(layers "F.Cu" "F.Mask" "F.Paste")
			(net "USB_HUB2_TI_GRSTZ_MRP_PROG_FUNC1")
		)
		(pad "51" smd circle
			(at 2.750058 -4.400042 90)
			(size 0 0)
			(layers "F.Cu" "F.Mask" "F.Paste")
			(net "P1V2_CPU0_USB2_DVDD12")
		)
		(pad "52" smd circle
			(at 2.249932 -4.400042 90)
			(size 0 0)
			(layers "F.Cu" "F.Mask" "F.Paste")
			(net "P3V3_AUX_CPU0_USB2_AVDD33")
		)
		(pad "53" smd circle
			(at 1.75006 -4.400042 90)
			(size 0 0)
			(layers "F.Cu" "F.Mask" "F.Paste")
			(net "USB2_CPU0_P0_R2_DP")
		)
		(pad "54" smd circle
			(at 1.249934 -4.400042 90)
			(size 0 0)
			(layers "F.Cu" "F.Mask" "F.Paste")
			(net "USB2_CPU0_P0_R2_DN")
		)
		(pad "55" smd circle
			(at 0.750062 -4.400042 90)
			(size 0 0)
			(layers "F.Cu" "F.Mask" "F.Paste")
			(net "USB3_CPU0_BMC_RX_HUB2_DP")
		)
		(pad "56" smd circle
			(at 0.249936 -4.400042 90)
			(size 0 0)
			(layers "F.Cu" "F.Mask" "F.Paste")
			(net "USB3_CPU0_BMC_RX_HUB2_DN")
		)
		(pad "57" smd circle
			(at -0.249936 -4.400042 90)
			(size 0 0)
			(layers "F.Cu" "F.Mask" "F.Paste")
			(net "P1V2_CPU0_USB2_DVDD12")
		)
		(pad "58" smd circle
			(at -0.750062 -4.400042 90)
			(size 0 0)
			(layers "F.Cu" "F.Mask" "F.Paste")
			(net "USB3_CPU0_BMC_TX_C2_DP")
		)
		(pad "59" smd circle
			(at -1.249934 -4.400042 90)
			(size 0 0)
			(layers "F.Cu" "F.Mask" "F.Paste")
			(net "USB3_CPU0_BMC_TX_C2_DN")
		)
		(pad "60" smd circle
			(at -1.75006 -4.400042 90)
			(size 0 0)
			(layers "F.Cu" "F.Mask" "F.Paste")
			(net "USB_HUB2_TI_NC_MRP_ATEST")
		)
		(pad "61" smd circle
			(at -2.249932 -4.400042 90)
			(size 0 0)
			(layers "F.Cu" "F.Mask" "F.Paste")
			(net "XTAL_USB_CPU0_HUB2_XOUT")
		)
		(pad "62" smd circle
			(at -2.750058 -4.400042 90)
			(size 0 0)
			(layers "F.Cu" "F.Mask" "F.Paste")
			(net "XTAL_USB_CPU0_HUB2_XIN")
		)
		(pad "63" smd circle
			(at -3.24993 -4.400042 90)
			(size 0 0)
			(layers "F.Cu" "F.Mask" "F.Paste")
			(net "P3V3_AUX_CPU0_USB2_AVDD33")
		)
		(pad "64" smd circle
			(at -3.750056 -4.400042 90)
			(size 0 0)
			(layers "F.Cu" "F.Mask" "F.Paste")
			(net "USB_HUB2_TI_USB_R1_MRP_RBIAS")
		)
		(pad "TH" smd circle
			(at 0 0 90)
			(size 0 0)
			(layers "F.Cu" "F.Mask" "F.Paste")
			(net "GND")
		)
	)
)
